(kicad_pcb
	(version 20260206)
	(generator "pcbnew")
	(generator_version "10.0")
	(general
		(thickness 1.6)
		(legacy_teardrops no)
	)
	(paper "A4")
	(title_block
		(title "01162023_DA0F0TEBIF0_F0T_Expander_BD_F_brd_V02_OCP.brd")
		(comment 1 "Grand Teton / footprint 6602 of 9728 (PEX1), pads 1-116 of 2397")
	)
	(layers
		(0 "F.Cu" signal "TOP")
		(4 "In1.Cu" signal "GND")
		(6 "In2.Cu" signal "VCC")
		(8 "In3.Cu" signal "VCC1")
		(10 "In4.Cu" signal "GND1")
		(12 "In5.Cu" signal "IN1")
		(14 "In6.Cu" signal "GND2")
		(16 "In7.Cu" signal "IN2")
		(18 "In8.Cu" signal "GND3")
		(20 "In9.Cu" signal "IN3")
		(22 "In10.Cu" signal "GND4")
		(24 "In11.Cu" signal "IN4")
		(26 "In12.Cu" signal "GND5")
		(28 "In13.Cu" signal "IN5")
		(30 "In14.Cu" signal "GND6")
		(32 "In15.Cu" signal "IN6")
		(34 "In16.Cu" signal "GND7")
		(2 "B.Cu" signal "BOTTOM")
		(9 "F.Adhes" user "F.Adhesive")
		(11 "B.Adhes" user "B.Adhesive")
		(13 "F.Paste" user "Package Geometry/Pastemask Top")
		(15 "B.Paste" user "Package Geometry/Pastemask Bottom")
		(5 "F.SilkS" user "Ref Des/Silkscreen Top")
		(7 "B.SilkS" user "Ref Des/Silkscreen Bottom")
		(1 "F.Mask" user "Board Geometry/Soldermask Top")
		(3 "B.Mask" user "Board Geometry/Soldermask Bottom")
		(17 "Dwgs.User" user "User.Drawings")
		(19 "Cmts.User" user "User.Comments")
		(21 "Eco1.User" user "User.Eco1")
		(23 "Eco2.User" user "User.Eco2")
		(25 "Edge.Cuts" user "Board Geometry/Outline")
		(27 "Margin" user)
		(31 "F.CrtYd" user "Package Geometry/Place Bound Top")
		(29 "B.CrtYd" user "Package Geometry/Place Bound Bottom")
		(35 "F.Fab" user "Ref Des/Assembly Top")
		(33 "B.Fab" user "Ref Des/Assembly Bottom")
	)
	(footprint ""
		(layer "F.Cu")
		(at 175.749966 -295.89984)
		(property "Reference" "PEX1"
			(at -3.353562 35.593274 0)
			(unlocked yes)
			(layer "F.SilkS")
			(effects
				(font
					(size 2.032 1.524)
					(thickness 0.1524)
				)
				(justify left)
			)
		)
		(property "Value" ""
			(at 0 0 0)
			(layer "F.Fab")
			(effects
				(font
					(size 1.27 1.27)
				)
			)
		)
		(duplicate_pad_numbers_are_jumpers no)
		(pad "A2" smd circle
			(at -21.850096 -22.800056)
			(size 0.4572 0.4572)
			(layers "F.Cu" "F.Mask" "F.Paste")
			(net "GND")
		)
		(pad "A3" smd circle
			(at -20.899882 -22.800056)
			(size 0.4572 0.4572)
			(layers "F.Cu" "F.Mask" "F.Paste")
			(net "P5E_PEX1_STN7_RX_DN<123>")
		)
		(pad "A4" smd circle
			(at -19.949922 -22.800056)
			(size 0.4572 0.4572)
			(layers "F.Cu" "F.Mask" "F.Paste")
			(net "GND")
		)
		(pad "A5" smd circle
			(at -18.999962 -22.800056)
			(size 0.4572 0.4572)
			(layers "F.Cu" "F.Mask" "F.Paste")
			(net "P5E_PEX1_STN7_RX_DN<125>")
		)
		(pad "A6" smd circle
			(at -18.050002 -22.800056)
			(size 0.4572 0.4572)
			(layers "F.Cu" "F.Mask" "F.Paste")
			(net "GND")
		)
		(pad "A7" smd circle
			(at -17.100042 -22.800056)
			(size 0.4572 0.4572)
			(layers "F.Cu" "F.Mask" "F.Paste")
			(net "P5E_PEX1_STN7_RX_DN<127>")
		)
		(pad "A8" smd circle
			(at -16.150082 -22.800056)
			(size 0.4572 0.4572)
			(layers "F.Cu" "F.Mask" "F.Paste")
			(net "GND")
		)
		(pad "A9" smd circle
			(at -15.200122 -22.800056)
			(size 0.4572 0.4572)
			(layers "F.Cu" "F.Mask" "F.Paste")
			(net "P5E_PEX1_STN6_RX_DN<110>")
		)
		(pad "A10" smd circle
			(at -14.249908 -22.800056)
			(size 0.4572 0.4572)
			(layers "F.Cu" "F.Mask" "F.Paste")
			(net "GND")
		)
		(pad "A11" smd circle
			(at -13.299948 -22.800056)
			(size 0.4572 0.4572)
			(layers "F.Cu" "F.Mask" "F.Paste")
			(net "P5E_PEX1_STN6_RX_DN<108>")
		)
		(pad "A12" smd circle
			(at -12.349988 -22.800056)
			(size 0.4572 0.4572)
			(layers "F.Cu" "F.Mask" "F.Paste")
			(net "GND")
		)
		(pad "A13" smd circle
			(at -11.400028 -22.800056)
			(size 0.4572 0.4572)
			(layers "F.Cu" "F.Mask" "F.Paste")
			(net "P5E_PEX1_STN6_RX_DN<106>")
		)
		(pad "A14" smd circle
			(at -10.450068 -22.800056)
			(size 0.4572 0.4572)
			(layers "F.Cu" "F.Mask" "F.Paste")
			(net "GND")
		)
		(pad "A15" smd circle
			(at -9.500108 -22.800056)
			(size 0.4572 0.4572)
			(layers "F.Cu" "F.Mask" "F.Paste")
			(net "P5E_PEX1_STN6_RX_DN<104>")
		)
		(pad "A16" smd circle
			(at -8.549894 -22.800056)
			(size 0.4572 0.4572)
			(layers "F.Cu" "F.Mask" "F.Paste")
			(net "GND")
		)
		(pad "A17" smd circle
			(at -7.599934 -22.800056)
			(size 0.4572 0.4572)
			(layers "F.Cu" "F.Mask" "F.Paste")
			(net "P5E_PEX1_STN6_RX_DN<102>")
		)
		(pad "A18" smd circle
			(at -6.649974 -22.800056)
			(size 0.4572 0.4572)
			(layers "F.Cu" "F.Mask" "F.Paste")
			(net "GND")
		)
		(pad "A19" smd circle
			(at -5.700014 -22.800056)
			(size 0.4572 0.4572)
			(layers "F.Cu" "F.Mask" "F.Paste")
			(net "P5E_PEX1_STN6_RX_DN<100>")
		)
		(pad "A20" smd circle
			(at -4.750054 -22.800056)
			(size 0.4572 0.4572)
			(layers "F.Cu" "F.Mask" "F.Paste")
			(net "GND")
		)
		(pad "A21" smd circle
			(at -3.800094 -22.800056)
			(size 0.4572 0.4572)
			(layers "F.Cu" "F.Mask" "F.Paste")
			(net "P5E_PEX1_STN6_RX_DN<98>")
		)
		(pad "A22" smd circle
			(at -2.84988 -22.800056)
			(size 0.4572 0.4572)
			(layers "F.Cu" "F.Mask" "F.Paste")
			(net "GND")
		)
		(pad "A23" smd circle
			(at -1.89992 -22.800056)
			(size 0.4572 0.4572)
			(layers "F.Cu" "F.Mask" "F.Paste")
			(net "P5E_PEX1_STN6_RX_DN<96>")
		)
		(pad "A24" smd circle
			(at -0.94996 -22.800056)
			(size 0.4572 0.4572)
			(layers "F.Cu" "F.Mask" "F.Paste")
			(net "GND")
		)
		(pad "A25" smd circle
			(at 0 -22.800056)
			(size 0.4572 0.4572)
			(layers "F.Cu" "F.Mask" "F.Paste")
			(net "P5E_PEX1_STN5_RX_DN<81>")
		)
		(pad "A26" smd circle
			(at 0.94996 -22.800056)
			(size 0.4572 0.4572)
			(layers "F.Cu" "F.Mask" "F.Paste")
			(net "GND")
		)
		(pad "A27" smd circle
			(at 1.89992 -22.800056)
			(size 0.4572 0.4572)
			(layers "F.Cu" "F.Mask" "F.Paste")
			(net "P5E_PEX1_STN5_RX_DN<83>")
		)
		(pad "A28" smd circle
			(at 2.84988 -22.800056)
			(size 0.4572 0.4572)
			(layers "F.Cu" "F.Mask" "F.Paste")
			(net "GND")
		)
		(pad "A29" smd circle
			(at 3.800094 -22.800056)
			(size 0.4572 0.4572)
			(layers "F.Cu" "F.Mask" "F.Paste")
			(net "P5E_PEX1_STN5_RX_DN<85>")
		)
		(pad "A30" smd circle
			(at 4.750054 -22.800056)
			(size 0.4572 0.4572)
			(layers "F.Cu" "F.Mask" "F.Paste")
			(net "GND")
		)
		(pad "A31" smd circle
			(at 5.700014 -22.800056)
			(size 0.4572 0.4572)
			(layers "F.Cu" "F.Mask" "F.Paste")
			(net "P5E_PEX1_STN5_RX_DN<87>")
		)
		(pad "A32" smd circle
			(at 6.649974 -22.800056)
			(size 0.4572 0.4572)
			(layers "F.Cu" "F.Mask" "F.Paste")
			(net "GND")
		)
		(pad "A33" smd circle
			(at 7.599934 -22.800056)
			(size 0.4572 0.4572)
			(layers "F.Cu" "F.Mask" "F.Paste")
			(net "P5E_PEX1_STN5_RX_DN<89>")
		)
		(pad "A34" smd circle
			(at 8.549894 -22.800056)
			(size 0.4572 0.4572)
			(layers "F.Cu" "F.Mask" "F.Paste")
			(net "GND")
		)
		(pad "A35" smd circle
			(at 9.500108 -22.800056)
			(size 0.4572 0.4572)
			(layers "F.Cu" "F.Mask" "F.Paste")
			(net "P5E_PEX1_STN5_RX_DN<91>")
		)
		(pad "A36" smd circle
			(at 10.450068 -22.800056)
			(size 0.4572 0.4572)
			(layers "F.Cu" "F.Mask" "F.Paste")
			(net "GND")
		)
		(pad "A37" smd circle
			(at 11.400028 -22.800056)
			(size 0.4572 0.4572)
			(layers "F.Cu" "F.Mask" "F.Paste")
			(net "P5E_PEX1_STN5_RX_DN<93>")
		)
		(pad "A38" smd circle
			(at 12.349988 -22.800056)
			(size 0.4572 0.4572)
			(layers "F.Cu" "F.Mask" "F.Paste")
			(net "GND")
		)
		(pad "A39" smd circle
			(at 13.299948 -22.800056)
			(size 0.4572 0.4572)
			(layers "F.Cu" "F.Mask" "F.Paste")
			(net "P5E_PEX1_STN5_RX_DN<95>")
		)
		(pad "A40" smd circle
			(at 14.249908 -22.800056)
			(size 0.4572 0.4572)
			(layers "F.Cu" "F.Mask" "F.Paste")
			(net "GND")
		)
		(pad "A41" smd circle
			(at 15.200122 -22.800056)
			(size 0.4572 0.4572)
			(layers "F.Cu" "F.Mask" "F.Paste")
			(net "P5E_PEX1_STN4_RX_DN<78>")
		)
		(pad "A42" smd circle
			(at 16.150082 -22.800056)
			(size 0.4572 0.4572)
			(layers "F.Cu" "F.Mask" "F.Paste")
			(net "GND")
		)
		(pad "A43" smd circle
			(at 17.100042 -22.800056)
			(size 0.4572 0.4572)
			(layers "F.Cu" "F.Mask" "F.Paste")
			(net "P5E_PEX1_STN4_RX_DN<76>")
		)
		(pad "A44" smd circle
			(at 18.050002 -22.800056)
			(size 0.4572 0.4572)
			(layers "F.Cu" "F.Mask" "F.Paste")
			(net "GND")
		)
		(pad "A45" smd circle
			(at 18.999962 -22.800056)
			(size 0.4572 0.4572)
			(layers "F.Cu" "F.Mask" "F.Paste")
			(net "P5E_PEX1_STN4_RX_DN<74>")
		)
		(pad "A46" smd circle
			(at 19.949922 -22.800056)
			(size 0.4572 0.4572)
			(layers "F.Cu" "F.Mask" "F.Paste")
			(net "GND")
		)
		(pad "A47" smd circle
			(at 20.899882 -22.800056)
			(size 0.4572 0.4572)
			(layers "F.Cu" "F.Mask" "F.Paste")
			(net "P5E_PEX1_STN4_RX_DN<72>")
		)
		(pad "A48" smd circle
			(at 21.850096 -22.800056)
			(size 0.4572 0.4572)
			(layers "F.Cu" "F.Mask" "F.Paste")
			(net "GND")
		)
		(pad "AA1" smd circle
			(at -22.800056 -3.800094)
			(size 0.4572 0.4572)
			(layers "F.Cu" "F.Mask" "F.Paste")
			(net "CLK_100M_PEX1_REF_R_DN")
		)
		(pad "AA2" smd circle
			(at -21.850096 -3.800094)
			(size 0.4572 0.4572)
			(layers "F.Cu" "F.Mask" "F.Paste")
			(net "CLK_100M_PEX1_REF_R_DP")
		)
		(pad "AA3" smd circle
			(at -20.899882 -3.800094)
			(size 0.4572 0.4572)
			(layers "F.Cu" "F.Mask" "F.Paste")
			(net "GND")
		)
		(pad "AA4" smd circle
			(at -19.949922 -3.800094)
			(size 0.4572 0.4572)
			(layers "F.Cu" "F.Mask" "F.Paste")
			(net "GND")
		)
		(pad "AA5" smd circle
			(at -18.999962 -3.800094)
			(size 0.4572 0.4572)
			(layers "F.Cu" "F.Mask" "F.Paste")
			(net "GND")
		)
		(pad "AA6" smd circle
			(at -18.050002 -3.800094)
			(size 0.4572 0.4572)
			(layers "F.Cu" "F.Mask" "F.Paste")
			(net "GND")
		)
		(pad "AA7" smd circle
			(at -17.100042 -3.800094)
			(size 0.4572 0.4572)
			(layers "F.Cu" "F.Mask" "F.Paste")
			(net "GND")
		)
		(pad "AA8" smd circle
			(at -16.150082 -3.800094)
			(size 0.4572 0.4572)
			(layers "F.Cu" "F.Mask" "F.Paste")
			(net "GND")
		)
		(pad "AA9" smd circle
			(at -15.200122 -3.800094)
			(size 0.4572 0.4572)
			(layers "F.Cu" "F.Mask" "F.Paste")
			(net "GND")
		)
		(pad "AA10" smd circle
			(at -14.249908 -3.800094)
			(size 0.4572 0.4572)
			(layers "F.Cu" "F.Mask" "F.Paste")
			(net "P1V8_VDDA_PEX1")
		)
		(pad "AA11" smd circle
			(at -13.299948 -3.800094)
			(size 0.4572 0.4572)
			(layers "F.Cu" "F.Mask" "F.Paste")
			(net "GND")
		)
		(pad "AA12" smd circle
			(at -12.349988 -3.800094)
			(size 0.4572 0.4572)
			(layers "F.Cu" "F.Mask" "F.Paste")
			(net "GND")
		)
		(pad "AA13" smd circle
			(at -11.400028 -3.800094)
			(size 0.4572 0.4572)
			(layers "F.Cu" "F.Mask" "F.Paste")
			(net "PCEPLL0_VDDA18_PEX1")
		)
		(pad "AA14" smd circle
			(at -10.450068 -3.800094)
			(size 0.4572 0.4572)
			(layers "F.Cu" "F.Mask" "F.Paste")
			(net "GND")
		)
		(pad "AA15" smd circle
			(at -9.500108 -3.800094)
			(size 0.4572 0.4572)
			(layers "F.Cu" "F.Mask" "F.Paste")
			(net "P0V8_PEX1")
		)
		(pad "AA16" smd circle
			(at -8.549894 -3.800094)
			(size 0.4572 0.4572)
			(layers "F.Cu" "F.Mask" "F.Paste")
			(net "GND")
		)
		(pad "AA17" smd circle
			(at -7.599934 -3.800094)
			(size 0.4572 0.4572)
			(layers "F.Cu" "F.Mask" "F.Paste")
			(net "GND")
		)
		(pad "AA18" smd circle
			(at -6.649974 -3.800094)
			(size 0.4572 0.4572)
			(layers "F.Cu" "F.Mask" "F.Paste")
			(net "GND")
		)
		(pad "AA19" smd circle
			(at -5.700014 -3.800094)
			(size 0.4572 0.4572)
			(layers "F.Cu" "F.Mask" "F.Paste")
			(net "GND")
		)
		(pad "AA20" smd circle
			(at -4.750054 -3.800094)
			(size 0.4572 0.4572)
			(layers "F.Cu" "F.Mask" "F.Paste")
			(net "GND")
		)
		(pad "AA21" smd circle
			(at -3.800094 -3.800094)
			(size 0.4572 0.4572)
			(layers "F.Cu" "F.Mask" "F.Paste")
			(net "GND")
		)
		(pad "AA22" smd circle
			(at -2.84988 -3.800094)
			(size 0.4572 0.4572)
			(layers "F.Cu" "F.Mask" "F.Paste")
			(net "GND")
		)
		(pad "AA23" smd circle
			(at -1.89992 -3.800094)
			(size 0.4572 0.4572)
			(layers "F.Cu" "F.Mask" "F.Paste")
			(net "GND")
		)
		(pad "AA24" smd circle
			(at -0.94996 -3.800094)
			(size 0.4572 0.4572)
			(layers "F.Cu" "F.Mask" "F.Paste")
			(net "GND")
		)
		(pad "AA25" smd circle
			(at 0 -3.800094)
			(size 0.4572 0.4572)
			(layers "F.Cu" "F.Mask" "F.Paste")
			(net "GND")
		)
		(pad "AA26" smd circle
			(at 0.94996 -3.800094)
			(size 0.4572 0.4572)
			(layers "F.Cu" "F.Mask" "F.Paste")
			(net "GND")
		)
		(pad "AA27" smd circle
			(at 1.89992 -3.800094)
			(size 0.4572 0.4572)
			(layers "F.Cu" "F.Mask" "F.Paste")
			(net "GND")
		)
		(pad "AA28" smd circle
			(at 2.84988 -3.800094)
			(size 0.4572 0.4572)
			(layers "F.Cu" "F.Mask" "F.Paste")
			(net "GND")
		)
		(pad "AA29" smd circle
			(at 3.800094 -3.800094)
			(size 0.4572 0.4572)
			(layers "F.Cu" "F.Mask" "F.Paste")
			(net "GND")
		)
		(pad "AA30" smd circle
			(at 4.750054 -3.800094)
			(size 0.4572 0.4572)
			(layers "F.Cu" "F.Mask" "F.Paste")
			(net "GND")
		)
		(pad "AA31" smd circle
			(at 5.700014 -3.800094)
			(size 0.4572 0.4572)
			(layers "F.Cu" "F.Mask" "F.Paste")
			(net "GND")
		)
		(pad "AA32" smd circle
			(at 6.649974 -3.800094)
			(size 0.4572 0.4572)
			(layers "F.Cu" "F.Mask" "F.Paste")
			(net "GND")
		)
		(pad "AA33" smd circle
			(at 7.599934 -3.800094)
			(size 0.4572 0.4572)
			(layers "F.Cu" "F.Mask" "F.Paste")
			(net "GND")
		)
		(pad "AA34" smd circle
			(at 8.549894 -3.800094)
			(size 0.4572 0.4572)
			(layers "F.Cu" "F.Mask" "F.Paste")
			(net "P1V8_VDDA_PEX1")
		)
		(pad "AA35" smd circle
			(at 9.500108 -3.800094)
			(size 0.4572 0.4572)
			(layers "F.Cu" "F.Mask" "F.Paste")
			(net "Net_506")
		)
		(pad "AA36" smd circle
			(at 10.450068 -3.800094)
			(size 0.4572 0.4572)
			(layers "F.Cu" "F.Mask" "F.Paste")
			(net "GND")
		)
		(pad "AA37" smd circle
			(at 11.400028 -3.800094)
			(size 0.4572 0.4572)
			(layers "F.Cu" "F.Mask" "F.Paste")
			(net "P1V8_VDDA_PEX1")
		)
		(pad "AA38" smd circle
			(at 12.349988 -3.800094)
			(size 0.4572 0.4572)
			(layers "F.Cu" "F.Mask" "F.Paste")
			(net "GND")
		)
		(pad "AA39" smd circle
			(at 13.299948 -3.800094)
			(size 0.4572 0.4572)
			(layers "F.Cu" "F.Mask" "F.Paste")
			(net "PEX1_ADCTEMP_VINP1")
		)
		(pad "AA40" smd circle
			(at 14.249908 -3.800094)
			(size 0.4572 0.4572)
			(layers "F.Cu" "F.Mask" "F.Paste")
			(net "GND")
		)
		(pad "AA41" smd circle
			(at 15.200122 -3.800094)
			(size 0.4572 0.4572)
			(layers "F.Cu" "F.Mask" "F.Paste")
			(net "GND")
		)
		(pad "AA42" smd circle
			(at 16.150082 -3.800094)
			(size 0.4572 0.4572)
			(layers "F.Cu" "F.Mask" "F.Paste")
			(net "GND")
		)
		(pad "AA43" smd circle
			(at 17.100042 -3.800094)
			(size 0.4572 0.4572)
			(layers "F.Cu" "F.Mask" "F.Paste")
			(net "Net_1384")
		)
		(pad "AA44" smd circle
			(at 18.050002 -3.800094)
			(size 0.4572 0.4572)
			(layers "F.Cu" "F.Mask" "F.Paste")
			(net "Net_1377")
		)
		(pad "AA45" smd circle
			(at 18.999962 -3.800094)
			(size 0.4572 0.4572)
			(layers "F.Cu" "F.Mask" "F.Paste")
			(net "GND")
		)
		(pad "AA46" smd circle
			(at 19.949922 -3.800094)
			(size 0.4572 0.4572)
			(layers "F.Cu" "F.Mask" "F.Paste")
			(net "Net_1543")
		)
		(pad "AA47" smd circle
			(at 20.899882 -3.800094)
			(size 0.4572 0.4572)
			(layers "F.Cu" "F.Mask" "F.Paste")
			(net "Net_1628")
		)
		(pad "AA48" smd circle
			(at 21.850096 -3.800094)
			(size 0.4572 0.4572)
			(layers "F.Cu" "F.Mask" "F.Paste")
			(net "GND")
		)
		(pad "AA49" smd circle
			(at 22.800056 -3.800094)
			(size 0.4572 0.4572)
			(layers "F.Cu" "F.Mask" "F.Paste")
			(net "GND")
		)
		(pad "AB1" smd circle
			(at -22.800056 -2.84988)
			(size 0.4572 0.4572)
			(layers "F.Cu" "F.Mask" "F.Paste")
			(net "GND")
		)
		(pad "AB2" smd circle
			(at -21.850096 -2.84988)
			(size 0.4572 0.4572)
			(layers "F.Cu" "F.Mask" "F.Paste")
			(net "GND")
		)
		(pad "AB3" smd circle
			(at -20.899882 -2.84988)
			(size 0.4572 0.4572)
			(layers "F.Cu" "F.Mask" "F.Paste")
			(net "GND")
		)
		(pad "AB4" smd circle
			(at -19.949922 -2.84988)
			(size 0.4572 0.4572)
			(layers "F.Cu" "F.Mask" "F.Paste")
			(net "CLK_100M_DB800ZL_PEX1_S0_R_DN")
		)
		(pad "AB5" smd circle
			(at -18.999962 -2.84988)
			(size 0.4572 0.4572)
			(layers "F.Cu" "F.Mask" "F.Paste")
			(net "CLK_100M_DB800ZL_PEX1_S0_R_DP")
		)
		(pad "AB6" smd circle
			(at -18.050002 -2.84988)
			(size 0.4572 0.4572)
			(layers "F.Cu" "F.Mask" "F.Paste")
			(net "GND")
		)
		(pad "AB7" smd circle
			(at -17.100042 -2.84988)
			(size 0.4572 0.4572)
			(layers "F.Cu" "F.Mask" "F.Paste")
			(net "Net_5306")
		)
		(pad "AB8" smd circle
			(at -16.150082 -2.84988)
			(size 0.4572 0.4572)
			(layers "F.Cu" "F.Mask" "F.Paste")
			(net "Net_5305")
		)
		(pad "AB9" smd circle
			(at -15.200122 -2.84988)
			(size 0.4572 0.4572)
			(layers "F.Cu" "F.Mask" "F.Paste")
			(net "GND")
		)
		(pad "AB10" smd circle
			(at -14.249908 -2.84988)
			(size 0.4572 0.4572)
			(layers "F.Cu" "F.Mask" "F.Paste")
			(net "P1V8_VDDA_PEX1")
		)
		(pad "AB11" smd circle
			(at -13.299948 -2.84988)
			(size 0.4572 0.4572)
			(layers "F.Cu" "F.Mask" "F.Paste")
			(net "GND")
		)
		(pad "AB12" smd circle
			(at -12.349988 -2.84988)
			(size 0.4572 0.4572)
			(layers "F.Cu" "F.Mask" "F.Paste")
			(net "PCEPLL1_VDDA18_PEX1")
		)
		(pad "AB13" smd circle
			(at -11.400028 -2.84988)
			(size 0.4572 0.4572)
			(layers "F.Cu" "F.Mask" "F.Paste")
			(net "GND")
		)
		(pad "AB14" smd circle
			(at -10.450068 -2.84988)
			(size 0.4572 0.4572)
			(layers "F.Cu" "F.Mask" "F.Paste")
			(net "P0V8_PEX1")
		)
		(pad "AB15" smd circle
			(at -9.500108 -2.84988)
			(size 0.4572 0.4572)
			(layers "F.Cu" "F.Mask" "F.Paste")
			(net "GND")
		)
		(pad "AB16" smd circle
			(at -8.549894 -2.84988)
			(size 0.4572 0.4572)
			(layers "F.Cu" "F.Mask" "F.Paste")
			(net "P0V8_SERDES_VDDA_PEX1")
		)
		(pad "AB17" smd circle
			(at -7.599934 -2.84988)
			(size 0.4572 0.4572)
			(layers "F.Cu" "F.Mask" "F.Paste")
			(net "P0V8_SERDES_VDDA_PEX1")
		)
		(pad "AB18" smd circle
			(at -6.649974 -2.84988)
			(size 0.4572 0.4572)
			(layers "F.Cu" "F.Mask" "F.Paste")
			(net "P0V8_SERDES_VDDA_PEX1")
		)
		(pad "AB19" smd circle
			(at -5.700014 -2.84988)
			(size 0.4572 0.4572)
			(layers "F.Cu" "F.Mask" "F.Paste")
			(net "P0V8_SERDES_VDDA_PEX1")
		)
		(pad "AB20" smd circle
			(at -4.750054 -2.84988)
			(size 0.4572 0.4572)
			(layers "F.Cu" "F.Mask" "F.Paste")
			(net "P0V8_SERDES_VDDA_PEX1")
		)
	)
)
